(kicad_pcb
	(version 20260206)
	(generator "pcbnew")
	(generator_version "10.0")
	(general
		(thickness 1.6)
		(legacy_teardrops no)
	)
	(paper "A4")
	(title_block
		(title "baseboard — 13948-1b.1110WZS1818.brd")
		(comment 1 "Honey Badger (Wiwynn) / footprints 376-383 of 2523")
	)
	(layers
		(0 "F.Cu" signal "TOP")
		(4 "In1.Cu" signal "L2GND")
		(6 "In2.Cu" signal "L3")
		(8 "In3.Cu" signal "L4VCC")
		(10 "In4.Cu" signal "L5VCC")
		(12 "In5.Cu" signal "L6")
		(14 "In6.Cu" signal "L7GND")
		(2 "B.Cu" signal "BOTTOM")
		(9 "F.Adhes" user "F.Adhesive")
		(11 "B.Adhes" user "B.Adhesive")
		(13 "F.Paste" user "Package Geometry/Pastemask Top")
		(15 "B.Paste" user "Package Geometry/Pastemask Bottom")
		(5 "F.SilkS" user "Ref Des/Silkscreen Top")
		(7 "B.SilkS" user "Ref Des/Silkscreen Bottom")
		(1 "F.Mask" user "Board Geometry/Soldermask Top")
		(3 "B.Mask" user "Board Geometry/Soldermask Bottom")
		(17 "Dwgs.User" user "User.Drawings")
		(19 "Cmts.User" user "User.Comments")
		(21 "Eco1.User" user "User.Eco1")
		(23 "Eco2.User" user "User.Eco2")
		(25 "Edge.Cuts" user "Board Geometry/Outline")
		(27 "Margin" user)
		(31 "F.CrtYd" user "Package Geometry/Place Bound Top")
		(29 "B.CrtYd" user "Package Geometry/Place Bound Bottom")
		(35 "F.Fab" user "Ref Des/Assembly Top")
		(33 "B.Fab" user "Ref Des/Assembly Bottom")
	)
	(footprint ""
		(layer "F.Cu")
		(at 23.064216 -206.04988 90)
		(property "Reference" "R569"
			(at 0 0 90)
			(layer "F.SilkS")
			(hide yes)
			(effects
				(font
					(size 1.27 1.27)
				)
			)
		)
		(property "Value" "4K7R2F-GP"
			(at 0.064008 -3.993896 90)
			(unlocked yes)
			(layer "F.Fab")
			(hide yes)
			(effects
				(font
					(size 1.016 1.016)
					(thickness 0.1524)
				)
			)
		)
		(property "Device Type" "R402H16"
			(at 0.064008 -5.517896 90)
			(unlocked yes)
			(layer "F.Fab")
			(hide yes)
			(effects
				(font
					(size 1.016 1.016)
					(thickness 0.1524)
				)
			)
		)
		(duplicate_pad_numbers_are_jumpers no)
		(fp_line
			(start 0.508 -0.9398)
			(end -0.508 -0.9398)
			(stroke
				(width 0.1524)
				(type default)
			)
			(layer "F.SilkS")
		)
		(fp_line
			(start -0.508 -0.9398)
			(end -0.508 0.9398)
			(stroke
				(width 0.1524)
				(type default)
			)
			(layer "F.SilkS")
		)
		(fp_rect
			(start -0.508 0.9398)
			(end 0.508 -0.9398)
			(stroke
				(width 0)
				(type default)
			)
			(fill no)
			(layer "F.CrtYd")
		)
		(fp_rect
			(start -0.508 0.9398)
			(end 0.508 -0.9398)
			(stroke
				(width 0)
				(type default)
			)
			(fill no)
			(layer "F.Fab")
		)
		(pad "1" smd custom
			(at 0 -0.4445 90)
			(size 0.1397 0.1397)
			(layers "F.Cu" "F.Mask" "F.Paste")
			(net "P3V3_STBY")
			(options
				(clearance outline)
				(anchor circle)
			)
			(primitives
				(gr_poly
					(pts
						(arc
							(start -0.1778 -0.2794)
							(mid -0.249642 -0.249642)
							(end -0.2794 -0.1778)
						)
						(arc
							(start -0.2794 0.1778)
							(mid -0.249642 0.249642)
							(end -0.1778 0.2794)
						)
						(arc
							(start 0.1778 0.2794)
							(mid 0.249642 0.249642)
							(end 0.2794 0.1778)
						)
						(arc
							(start 0.2794 -0.1778)
							(mid 0.249642 -0.249642)
							(end 0.1778 -0.2794)
						)
					)
					(width 0)
					(fill yes)
				)
			)
		)
		(pad "2" smd custom
			(at 0 0.4445 90)
			(size 0.1397 0.1397)
			(layers "F.Cu" "F.Mask" "F.Paste")
			(net "VOL_SEN_ADDR_U17")
			(options
				(clearance outline)
				(anchor circle)
			)
			(primitives
				(gr_poly
					(pts
						(arc
							(start -0.1778 -0.2794)
							(mid -0.249642 -0.249642)
							(end -0.2794 -0.1778)
						)
						(arc
							(start -0.2794 0.1778)
							(mid -0.249642 0.249642)
							(end -0.1778 0.2794)
						)
						(arc
							(start 0.1778 0.2794)
							(mid 0.249642 0.249642)
							(end 0.2794 0.1778)
						)
						(arc
							(start 0.2794 -0.1778)
							(mid 0.249642 -0.249642)
							(end 0.1778 -0.2794)
						)
					)
					(width 0)
					(fill yes)
				)
			)
		)
	)
	(footprint ""
		(layer "F.Cu")
		(at 62.357 -218.313 90)
		(property "Reference" "R1226"
			(at 0 0 90)
			(layer "F.SilkS")
			(hide yes)
			(effects
				(font
					(size 1.27 1.27)
				)
			)
		)
		(property "Value" "11KR2F-L-GP"
			(at 0.064008 -3.993896 90)
			(unlocked yes)
			(layer "F.Fab")
			(hide yes)
			(effects
				(font
					(size 1.016 1.016)
					(thickness 0.1524)
				)
			)
		)
		(property "Device Type" "R402H16"
			(at 0.064008 -5.517896 90)
			(unlocked yes)
			(layer "F.Fab")
			(hide yes)
			(effects
				(font
					(size 1.016 1.016)
					(thickness 0.1524)
				)
			)
		)
		(duplicate_pad_numbers_are_jumpers no)
		(fp_line
			(start 0.508 -0.9398)
			(end -0.508 -0.9398)
			(stroke
				(width 0.1524)
				(type default)
			)
			(layer "F.SilkS")
		)
		(fp_line
			(start -0.508 -0.9398)
			(end -0.508 0.9398)
			(stroke
				(width 0.1524)
				(type default)
			)
			(layer "F.SilkS")
		)
		(fp_rect
			(start -0.508 0.9398)
			(end 0.508 -0.9398)
			(stroke
				(width 0)
				(type default)
			)
			(fill no)
			(layer "F.CrtYd")
		)
		(fp_rect
			(start -0.508 0.9398)
			(end 0.508 -0.9398)
			(stroke
				(width 0)
				(type default)
			)
			(fill no)
			(layer "F.Fab")
		)
		(pad "1" smd custom
			(at 0 -0.4445 90)
			(size 0.1397 0.1397)
			(layers "F.Cu" "F.Mask" "F.Paste")
			(net "MB0_P12V_PWGIN_R")
			(options
				(clearance outline)
				(anchor circle)
			)
			(primitives
				(gr_poly
					(pts
						(arc
							(start -0.1778 -0.2794)
							(mid -0.249642 -0.249642)
							(end -0.2794 -0.1778)
						)
						(arc
							(start -0.2794 0.1778)
							(mid -0.249642 0.249642)
							(end -0.1778 0.2794)
						)
						(arc
							(start 0.1778 0.2794)
							(mid 0.249642 0.249642)
							(end 0.2794 0.1778)
						)
						(arc
							(start 0.2794 -0.1778)
							(mid 0.249642 -0.249642)
							(end 0.1778 -0.2794)
						)
					)
					(width 0)
					(fill yes)
				)
			)
		)
		(pad "2" smd custom
			(at 0 0.4445 90)
			(size 0.1397 0.1397)
			(layers "F.Cu" "F.Mask" "F.Paste")
			(net "AGND_CURRENT_MON")
			(options
				(clearance outline)
				(anchor circle)
			)
			(primitives
				(gr_poly
					(pts
						(arc
							(start -0.1778 -0.2794)
							(mid -0.249642 -0.249642)
							(end -0.2794 -0.1778)
						)
						(arc
							(start -0.2794 0.1778)
							(mid -0.249642 0.249642)
							(end -0.1778 0.2794)
						)
						(arc
							(start 0.1778 0.2794)
							(mid 0.249642 0.249642)
							(end 0.2794 0.1778)
						)
						(arc
							(start 0.2794 -0.1778)
							(mid 0.249642 -0.249642)
							(end 0.1778 -0.2794)
						)
					)
					(width 0)
					(fill yes)
				)
			)
		)
	)
	(footprint ""
		(layer "F.Cu")
		(at 46.62297 -133.477 90)
		(property "Reference" "SR860"
			(at 0 0 90)
			(layer "F.SilkS")
			(hide yes)
			(effects
				(font
					(size 1.27 1.27)
				)
			)
		)
		(property "Value" "1KR2J-1-GP"
			(at 0.064008 -3.993896 90)
			(unlocked yes)
			(layer "F.Fab")
			(hide yes)
			(effects
				(font
					(size 1.016 1.016)
					(thickness 0.1524)
				)
			)
		)
		(property "Device Type" "R402H16"
			(at 0.064008 -5.517896 90)
			(unlocked yes)
			(layer "F.Fab")
			(hide yes)
			(effects
				(font
					(size 1.016 1.016)
					(thickness 0.1524)
				)
			)
		)
		(duplicate_pad_numbers_are_jumpers no)
		(fp_line
			(start 0.508 -0.9398)
			(end -0.508 -0.9398)
			(stroke
				(width 0.1524)
				(type default)
			)
			(layer "F.SilkS")
		)
		(fp_line
			(start -0.508 -0.9398)
			(end -0.508 0.9398)
			(stroke
				(width 0.1524)
				(type default)
			)
			(layer "F.SilkS")
		)
		(fp_rect
			(start -0.508 0.9398)
			(end 0.508 -0.9398)
			(stroke
				(width 0)
				(type default)
			)
			(fill no)
			(layer "F.CrtYd")
		)
		(fp_rect
			(start -0.508 0.9398)
			(end 0.508 -0.9398)
			(stroke
				(width 0)
				(type default)
			)
			(fill no)
			(layer "F.Fab")
		)
		(pad "1" smd custom
			(at 0 -0.4445 90)
			(size 0.1397 0.1397)
			(layers "F.Cu" "F.Mask" "F.Paste")
			(net "EXP_RST_R")
			(options
				(clearance outline)
				(anchor circle)
			)
			(primitives
				(gr_poly
					(pts
						(arc
							(start -0.1778 -0.2794)
							(mid -0.249642 -0.249642)
							(end -0.2794 -0.1778)
						)
						(arc
							(start -0.2794 0.1778)
							(mid -0.249642 0.249642)
							(end -0.1778 0.2794)
						)
						(arc
							(start 0.1778 0.2794)
							(mid 0.249642 0.249642)
							(end 0.2794 0.1778)
						)
						(arc
							(start 0.2794 -0.1778)
							(mid 0.249642 -0.249642)
							(end 0.1778 -0.2794)
						)
					)
					(width 0)
					(fill yes)
				)
			)
		)
		(pad "2" smd custom
			(at 0 0.4445 90)
			(size 0.1397 0.1397)
			(layers "F.Cu" "F.Mask" "F.Paste")
			(net "P1V8_E")
			(options
				(clearance outline)
				(anchor circle)
			)
			(primitives
				(gr_poly
					(pts
						(arc
							(start -0.1778 -0.2794)
							(mid -0.249642 -0.249642)
							(end -0.2794 -0.1778)
						)
						(arc
							(start -0.2794 0.1778)
							(mid -0.249642 0.249642)
							(end -0.1778 0.2794)
						)
						(arc
							(start 0.1778 0.2794)
							(mid 0.249642 0.249642)
							(end 0.2794 0.1778)
						)
						(arc
							(start 0.2794 -0.1778)
							(mid 0.249642 -0.249642)
							(end 0.1778 -0.2794)
						)
					)
					(width 0)
					(fill yes)
				)
			)
		)
	)
	(footprint ""
		(layer "F.Cu")
		(at 305.181 -216.789)
		(property "Reference" "R656"
			(at 0 0 0)
			(layer "F.SilkS")
			(hide yes)
			(effects
				(font
					(size 1.27 1.27)
				)
			)
		)
		(property "Value" "0R2J-2-GP"
			(at 0.064008 -3.993896 0)
			(unlocked yes)
			(layer "F.Fab")
			(hide yes)
			(effects
				(font
					(size 1.016 1.016)
					(thickness 0.1524)
				)
			)
		)
		(property "Device Type" "R402H16"
			(at 0.064008 -5.517896 0)
			(unlocked yes)
			(layer "F.Fab")
			(hide yes)
			(effects
				(font
					(size 1.016 1.016)
					(thickness 0.1524)
				)
			)
		)
		(duplicate_pad_numbers_are_jumpers no)
		(fp_line
			(start -0.508 -0.9398)
			(end -0.508 0.9398)
			(stroke
				(width 0.1524)
				(type default)
			)
			(layer "F.SilkS")
		)
		(fp_line
			(start 0.508 -0.9398)
			(end -0.508 -0.9398)
			(stroke
				(width 0.1524)
				(type default)
			)
			(layer "F.SilkS")
		)
		(fp_rect
			(start -0.508 0.9398)
			(end 0.508 -0.9398)
			(stroke
				(width 0)
				(type default)
			)
			(fill no)
			(layer "F.CrtYd")
		)
		(fp_rect
			(start -0.508 0.9398)
			(end 0.508 -0.9398)
			(stroke
				(width 0)
				(type default)
			)
			(fill no)
			(layer "F.Fab")
		)
		(pad "1" smd custom
			(at 0 -0.4445)
			(size 0.1397 0.1397)
			(layers "F.Cu" "F.Mask" "F.Paste")
			(net "BMC_DEBUG_OE_1_N")
			(options
				(clearance outline)
				(anchor circle)
			)
			(primitives
				(gr_poly
					(pts
						(arc
							(start -0.1778 -0.2794)
							(mid -0.249642 -0.249642)
							(end -0.2794 -0.1778)
						)
						(arc
							(start -0.2794 0.1778)
							(mid -0.249642 0.249642)
							(end -0.1778 0.2794)
						)
						(arc
							(start 0.1778 0.2794)
							(mid 0.249642 0.249642)
							(end 0.2794 0.1778)
						)
						(arc
							(start 0.2794 -0.1778)
							(mid 0.249642 -0.249642)
							(end 0.1778 -0.2794)
						)
					)
					(width 0)
					(fill yes)
				)
			)
		)
		(pad "2" smd custom
			(at 0 0.4445)
			(size 0.1397 0.1397)
			(layers "F.Cu" "F.Mask" "F.Paste")
			(net "BMC0_TACH9")
			(options
				(clearance outline)
				(anchor circle)
			)
			(primitives
				(gr_poly
					(pts
						(arc
							(start -0.1778 -0.2794)
							(mid -0.249642 -0.249642)
							(end -0.2794 -0.1778)
						)
						(arc
							(start -0.2794 0.1778)
							(mid -0.249642 0.249642)
							(end -0.1778 0.2794)
						)
						(arc
							(start 0.1778 0.2794)
							(mid 0.249642 0.249642)
							(end 0.2794 0.1778)
						)
						(arc
							(start 0.2794 -0.1778)
							(mid 0.249642 -0.249642)
							(end 0.1778 -0.2794)
						)
					)
					(width 0)
					(fill yes)
				)
			)
		)
	)
	(footprint ""
		(layer "F.Cu")
		(at 181.283864 -38.172136 180)
		(property "Reference" "R392"
			(at 0 0 180)
			(layer "F.SilkS")
			(hide yes)
			(effects
				(font
					(size 1.27 1.27)
				)
			)
		)
		(property "Value" "4K75R2F-1-GP"
			(at 0.064008 -3.993896 180)
			(unlocked yes)
			(layer "F.Fab")
			(hide yes)
			(effects
				(font
					(size 1.016 1.016)
					(thickness 0.1524)
				)
			)
		)
		(property "Device Type" "R402H16"
			(at 0.064008 -5.517896 180)
			(unlocked yes)
			(layer "F.Fab")
			(hide yes)
			(effects
				(font
					(size 1.016 1.016)
					(thickness 0.1524)
				)
			)
		)
		(duplicate_pad_numbers_are_jumpers no)
		(fp_line
			(start 0.508 -0.9398)
			(end -0.508 -0.9398)
			(stroke
				(width 0.1524)
				(type default)
			)
			(layer "F.SilkS")
		)
		(fp_line
			(start -0.508 -0.9398)
			(end -0.508 0.9398)
			(stroke
				(width 0.1524)
				(type default)
			)
			(layer "F.SilkS")
		)
		(fp_rect
			(start -0.508 0.9398)
			(end 0.508 -0.9398)
			(stroke
				(width 0)
				(type default)
			)
			(fill no)
			(layer "F.CrtYd")
		)
		(fp_rect
			(start -0.508 0.9398)
			(end 0.508 -0.9398)
			(stroke
				(width 0)
				(type default)
			)
			(fill no)
			(layer "F.Fab")
		)
		(pad "1" smd custom
			(at 0 -0.4445 180)
			(size 0.1397 0.1397)
			(layers "F.Cu" "F.Mask" "F.Paste")
			(net "PHY_AD3")
			(options
				(clearance outline)
				(anchor circle)
			)
			(primitives
				(gr_poly
					(pts
						(arc
							(start -0.1778 -0.2794)
							(mid -0.249642 -0.249642)
							(end -0.2794 -0.1778)
						)
						(arc
							(start -0.2794 0.1778)
							(mid -0.249642 0.249642)
							(end -0.1778 0.2794)
						)
						(arc
							(start 0.1778 0.2794)
							(mid 0.249642 0.249642)
							(end 0.2794 0.1778)
						)
						(arc
							(start 0.2794 -0.1778)
							(mid 0.249642 -0.249642)
							(end 0.1778 -0.2794)
						)
					)
					(width 0)
					(fill yes)
				)
			)
		)
		(pad "2" smd custom
			(at 0 0.4445 180)
			(size 0.1397 0.1397)
			(layers "F.Cu" "F.Mask" "F.Paste")
			(net "GND")
			(options
				(clearance outline)
				(anchor circle)
			)
			(primitives
				(gr_poly
					(pts
						(arc
							(start -0.1778 -0.2794)
							(mid -0.249642 -0.249642)
							(end -0.2794 -0.1778)
						)
						(arc
							(start -0.2794 0.1778)
							(mid -0.249642 0.249642)
							(end -0.1778 0.2794)
						)
						(arc
							(start 0.1778 0.2794)
							(mid 0.249642 0.249642)
							(end 0.2794 0.1778)
						)
						(arc
							(start 0.2794 -0.1778)
							(mid 0.249642 -0.249642)
							(end 0.1778 -0.2794)
						)
					)
					(width 0)
					(fill yes)
				)
			)
		)
	)
	(footprint ""
		(layer "F.Cu")
		(at 92.34297 -112.014 180)
		(property "Reference" "SC1231"
			(at 0 0 180)
			(layer "F.SilkS")
			(hide yes)
			(effects
				(font
					(size 1.27 1.27)
				)
			)
		)
		(property "Value" "SCD1U6D3V1KX-GP"
			(at -2.8321 -1.7399 180)
			(unlocked yes)
			(layer "F.Fab")
			(hide yes)
			(effects
				(font
					(size 1.016 1.016)
					(thickness 0.1524)
				)
			)
		)
		(property "Device Type" "C0201H13"
			(at -2.8321 -3.2639 180)
			(unlocked yes)
			(layer "F.Fab")
			(hide yes)
			(effects
				(font
					(size 1.016 1.016)
					(thickness 0.1524)
				)
			)
		)
		(duplicate_pad_numbers_are_jumpers no)
		(fp_rect
			(start -0.2794 0.6477)
			(end 0.2794 -0.6477)
			(stroke
				(width 0)
				(type default)
			)
			(fill no)
			(layer "F.CrtYd")
		)
		(fp_rect
			(start -0.2794 0.6477)
			(end 0.2794 -0.6477)
			(stroke
				(width 0)
				(type default)
			)
			(fill no)
			(layer "F.Fab")
		)
		(pad "1" smd custom
			(at 0 -0.2794 180)
			(size 0.0762 0.0762)
			(layers "F.Cu" "F.Mask" "F.Paste")
			(net "P1V8_E")
			(options
				(clearance outline)
				(anchor circle)
			)
			(primitives
				(gr_poly
					(pts
						(arc
							(start 0.1524 -0.127)
							(mid 0.137521 -0.162921)
							(end 0.1016 -0.1778)
						)
						(arc
							(start -0.1016 -0.1778)
							(mid -0.137521 -0.162921)
							(end -0.1524 -0.127)
						)
						(arc
							(start -0.1524 0.127)
							(mid -0.137521 0.162921)
							(end -0.1016 0.1778)
						)
						(arc
							(start 0.1016 0.1778)
							(mid 0.137521 0.162921)
							(end 0.1524 0.127)
						)
					)
					(width 0)
					(fill yes)
				)
			)
		)
		(pad "2" smd custom
			(at 0 0.2794 180)
			(size 0.0762 0.0762)
			(layers "F.Cu" "F.Mask" "F.Paste")
			(net "GND")
			(options
				(clearance outline)
				(anchor circle)
			)
			(primitives
				(gr_poly
					(pts
						(arc
							(start 0.1524 -0.127)
							(mid 0.137521 -0.162921)
							(end 0.1016 -0.1778)
						)
						(arc
							(start -0.1016 -0.1778)
							(mid -0.137521 -0.162921)
							(end -0.1524 -0.127)
						)
						(arc
							(start -0.1524 0.127)
							(mid -0.137521 0.162921)
							(end -0.1016 0.1778)
						)
						(arc
							(start 0.1016 0.1778)
							(mid 0.137521 0.162921)
							(end 0.1524 0.127)
						)
					)
					(width 0)
					(fill yes)
				)
			)
		)
	)
	(footprint ""
		(layer "F.Cu")
		(at 307.648864 -205.096872)
		(property "Reference" "R169"
			(at 0 0 0)
			(layer "F.SilkS")
			(hide yes)
			(effects
				(font
					(size 1.27 1.27)
				)
			)
		)
		(property "Value" "0R2J-2-GP"
			(at 0.064008 -3.993896 0)
			(unlocked yes)
			(layer "F.Fab")
			(hide yes)
			(effects
				(font
					(size 1.016 1.016)
					(thickness 0.1524)
				)
			)
		)
		(property "Device Type" "R402H16"
			(at 0.064008 -5.517896 0)
			(unlocked yes)
			(layer "F.Fab")
			(hide yes)
			(effects
				(font
					(size 1.016 1.016)
					(thickness 0.1524)
				)
			)
		)
		(duplicate_pad_numbers_are_jumpers no)
		(fp_line
			(start -0.508 -0.9398)
			(end -0.508 0.9398)
			(stroke
				(width 0.1524)
				(type default)
			)
			(layer "F.SilkS")
		)
		(fp_line
			(start 0.508 -0.9398)
			(end -0.508 -0.9398)
			(stroke
				(width 0.1524)
				(type default)
			)
			(layer "F.SilkS")
		)
		(fp_rect
			(start -0.508 0.9398)
			(end 0.508 -0.9398)
			(stroke
				(width 0)
				(type default)
			)
			(fill no)
			(layer "F.CrtYd")
		)
		(fp_rect
			(start -0.508 0.9398)
			(end 0.508 -0.9398)
			(stroke
				(width 0)
				(type default)
			)
			(fill no)
			(layer "F.Fab")
		)
		(pad "1" smd custom
			(at 0 -0.4445)
			(size 0.1397 0.1397)
			(layers "F.Cu" "F.Mask" "F.Paste")
			(net "BMC_I2C_A_SDA")
			(options
				(clearance outline)
				(anchor circle)
			)
			(primitives
				(gr_poly
					(pts
						(arc
							(start -0.1778 -0.2794)
							(mid -0.249642 -0.249642)
							(end -0.2794 -0.1778)
						)
						(arc
							(start -0.2794 0.1778)
							(mid -0.249642 0.249642)
							(end -0.1778 0.2794)
						)
						(arc
							(start 0.1778 0.2794)
							(mid 0.249642 0.249642)
							(end 0.2794 0.1778)
						)
						(arc
							(start 0.2794 -0.1778)
							(mid 0.249642 -0.249642)
							(end 0.1778 -0.2794)
						)
					)
					(width 0)
					(fill yes)
				)
			)
		)
		(pad "2" smd custom
			(at 0 0.4445)
			(size 0.1397 0.1397)
			(layers "F.Cu" "F.Mask" "F.Paste")
			(net "LED_DR_I2C_SDA")
			(options
				(clearance outline)
				(anchor circle)
			)
			(primitives
				(gr_poly
					(pts
						(arc
							(start -0.1778 -0.2794)
							(mid -0.249642 -0.249642)
							(end -0.2794 -0.1778)
						)
						(arc
							(start -0.2794 0.1778)
							(mid -0.249642 0.249642)
							(end -0.1778 0.2794)
						)
						(arc
							(start 0.1778 0.2794)
							(mid 0.249642 0.249642)
							(end 0.2794 0.1778)
						)
						(arc
							(start 0.2794 -0.1778)
							(mid 0.249642 -0.249642)
							(end 0.1778 -0.2794)
						)
					)
					(width 0)
					(fill yes)
				)
			)
		)
	)
	(footprint ""
		(layer "F.Cu")
		(at 98.43897 -116.7638)
		(property "Reference" "TP261"
			(at 0 0 0)
			(layer "F.SilkS")
			(hide yes)
			(effects
				(font
					(size 1.27 1.27)
				)
			)
		)
		(property "Value" "TPAD28"
			(at 0.0127 -1.8034 0)
			(unlocked yes)
			(layer "F.Fab")
			(hide yes)
			(effects
				(font
					(size 1.016 1.016)
					(thickness 0.1524)
				)
			)
		)
		(property "Device Type" "TPAD28"
			(at 0.0127 -3.3274 0)
			(unlocked yes)
			(layer "F.Fab")
			(hide yes)
			(effects
				(font
					(size 1.016 1.016)
					(thickness 0.1524)
				)
			)
		)
		(duplicate_pad_numbers_are_jumpers no)
		(fp_poly
			(pts
				(arc
					(start 0.3556 0)
					(mid -0.3556 0)
					(end 0.3556 0)
				)
			)
			(stroke
				(width 0)
				(type default)
			)
			(fill no)
			(layer "F.CrtYd")
		)
		(fp_poly
			(pts
				(arc
					(start 0.6096 0)
					(mid -0.6096 0)
					(end 0.6096 0)
				)
			)
			(stroke
				(width 0)
				(type default)
			)
			(fill no)
			(layer "F.Fab")
		)
		(pad "1" smd circle
			(at 0 0)
			(size 0.7112 0.7112)
			(layers "F.Cu" "F.Mask" "F.Paste")
			(net "EXP_SIO_CLK_IN")
		)
	)
)
